# BASEBOARD_FAB2 (Tioga Pass) — schematic netlist excerpt (pin names and nets, part order shuffled) for the footprints in the layout excerpt that follows; sources: Cadence DE-HDL packaged netlist, KiCad conversion of Wiwynn_Tioga_Pass_MB.brd

R7B11  RES  0.0 5% CHIP  pkg 0402  page 232 : A = PVPP_DEF ; B = VSENSE_PVPP_DEF
C8F13  CAP_A  0.01UF 25V 10% X7R  pkg 0402V  page 185 : A = SATA6G_S0_RX_DP ; B = P3E_PCH_M2_SATA6G_RX_R_DP
C1C15  CAP  1.0UF 16V 10% X6S  pkg 0402  page 210 : A = VR_FET_SW_P12V_STBY_PVCCIN_CPU1 ; B = GND

(kicad_pcb
	(version 20260206)
	(generator "pcbnew")
	(generator_version "10.0")
	(general
		(thickness 1.6)
		(legacy_teardrops no)
	)
	(paper "A4")
	(title_block
		(title "Wiwynn_Tioga_Pass_MB.brd")
		(comment 1 "Tioga Pass / footprints 2225-2227 of 4770")
	)
	(layers
		(0 "F.Cu" signal "TOP")
		(4 "In1.Cu" signal "L2GND")
		(6 "In2.Cu" signal "L3")
		(8 "In3.Cu" signal "L4GND")
		(10 "In4.Cu" signal "L5")
		(12 "In5.Cu" signal "L6GND")
		(14 "In6.Cu" signal "L7VCC")
		(16 "In7.Cu" signal "L8VCC")
		(18 "In8.Cu" signal "L9GND")
		(20 "In9.Cu" signal "L10")
		(22 "In10.Cu" signal "L11GND")
		(24 "In11.Cu" signal "L12")
		(26 "In12.Cu" signal "L13GND")
		(2 "B.Cu" signal "BOTTOM")
		(9 "F.Adhes" user "F.Adhesive")
		(11 "B.Adhes" user "B.Adhesive")
		(13 "F.Paste" user "Package Geometry/Pastemask Top")
		(15 "B.Paste" user "Package Geometry/Pastemask Bottom")
		(5 "F.SilkS" user "Ref Des/Silkscreen Top")
		(7 "B.SilkS" user "Ref Des/Silkscreen Bottom")
		(1 "F.Mask" user "Board Geometry/Soldermask Top")
		(3 "B.Mask" user "Board Geometry/Soldermask Bottom")
		(17 "Dwgs.User" user "User.Drawings")
		(19 "Cmts.User" user "User.Comments")
		(21 "Eco1.User" user "User.Eco1")
		(23 "Eco2.User" user "User.Eco2")
		(25 "Edge.Cuts" user "Board Geometry/Outline")
		(27 "Margin" user)
		(31 "F.CrtYd" user "Package Geometry/Place Bound Top")
		(29 "B.CrtYd" user "Package Geometry/Place Bound Bottom")
		(35 "F.Fab" user "Ref Des/Assembly Top")
		(33 "B.Fab" user "Ref Des/Assembly Bottom")
	)
	(footprint ""
		(layer "F.Cu")
		(at 377.5202 -29.232352 90)
		(property "Reference" "C8F13"
			(at -0.8382 -0.67818 90)
			(unlocked yes)
			(layer "F.SilkS")
			(effects
				(font
					(size 0.4064 0.254)
					(thickness 0.1524)
				)
				(justify left)
			)
		)
		(property "Value" ""
			(at 0 0 90)
			(layer "F.Fab")
			(effects
				(font
					(size 1.27 1.27)
				)
			)
		)
		(duplicate_pad_numbers_are_jumpers no)
		(fp_poly
			(pts
				(xy 0.3048 -0.1016) (xy 0.3048 0.9906) (xy -0.3048 0.9906) (xy -0.3048 -0.1016)
			)
			(stroke
				(width 0)
				(type default)
			)
			(fill no)
			(layer "F.CrtYd")
		)
		(fp_line
			(start 0.3048 -0.1016)
			(end -0.3048 -0.1016)
			(stroke
				(width 0.1)
				(type default)
			)
			(layer "F.Fab")
		)
		(fp_line
			(start -0.3048 -0.1016)
			(end -0.3048 0.9906)
			(stroke
				(width 0.1)
				(type default)
			)
			(layer "F.Fab")
		)
		(fp_line
			(start 0.3048 0.9906)
			(end 0.3048 -0.1016)
			(stroke
				(width 0.1)
				(type default)
			)
			(layer "F.Fab")
		)
		(fp_line
			(start -0.3048 0.9906)
			(end 0.3048 0.9906)
			(stroke
				(width 0.1)
				(type default)
			)
			(layer "F.Fab")
		)
		(pad "1" smd rect
			(at 0 0 90)
			(size 0.508 0.508)
			(layers "F.Cu" "F.Mask" "F.Paste")
			(net "SATA6G_S0_RX_DP")
		)
		(pad "2" smd rect
			(at 0 0.889 90)
			(size 0.508 0.508)
			(layers "F.Cu" "F.Mask" "F.Paste")
			(net "P3E_PCH_M2_SATA6G_RX_R_DP")
		)
		(zone
			(layer "F.Cu")
			(hatch none 0.5)
			(connect_pads
				(clearance 0)
			)
			(min_thickness 0.25)
			(keepout
				(tracks allowed)
				(vias not_allowed)
				(pads allowed)
				(copperpour not_allowed)
				(footprints allowed)
			)
			(placement
				(enabled no)
				(sheetname "")
			)
			(fill
				(thermal_gap 0.5)
				(thermal_bridge_width 0.5)
				(island_removal_mode 0)
			)
			(polygon
				(pts
					(xy 377.7742 -28.978352) (xy 377.7742 -29.486352) (xy 378.1552 -29.486352) (xy 378.1552 -28.978352)
				)
			)
		)
		(zone
			(layer "F.Cu")
			(hatch none 0.5)
			(connect_pads
				(clearance 0)
			)
			(min_thickness 0.25)
			(keepout
				(tracks not_allowed)
				(vias allowed)
				(pads allowed)
				(copperpour not_allowed)
				(footprints allowed)
			)
			(placement
				(enabled no)
				(sheetname "")
			)
			(fill
				(thermal_gap 0.5)
				(thermal_bridge_width 0.5)
				(island_removal_mode 0)
			)
			(polygon
				(pts
					(xy 378.1552 -28.978352) (xy 378.1552 -29.486352) (xy 377.7742 -29.486352) (xy 377.7742 -28.978352)
				)
			)
		)
	)
	(footprint ""
		(layer "F.Cu")
		(at 32.667194 -102.285292 90)
		(property "Reference" "C1C15"
			(at 0 0 90)
			(layer "F.SilkS")
			(hide yes)
			(effects
				(font
					(size 1.27 1.27)
				)
			)
		)
		(property "Value" ""
			(at 0 0 90)
			(layer "F.Fab")
			(effects
				(font
					(size 1.27 1.27)
				)
			)
		)
		(duplicate_pad_numbers_are_jumpers no)
		(fp_rect
			(start 0.3048 -0.1016)
			(end -0.3048 0.9906)
			(stroke
				(width 0)
				(type default)
			)
			(fill no)
			(layer "F.CrtYd")
		)
		(fp_line
			(start 0.3048 -0.1016)
			(end -0.3048 -0.1016)
			(stroke
				(width 0.1)
				(type default)
			)
			(layer "F.Fab")
		)
		(fp_line
			(start -0.3048 -0.1016)
			(end -0.3048 0.9906)
			(stroke
				(width 0.1)
				(type default)
			)
			(layer "F.Fab")
		)
		(fp_line
			(start 0.3048 0.9906)
			(end 0.3048 -0.1016)
			(stroke
				(width 0.1)
				(type default)
			)
			(layer "F.Fab")
		)
		(fp_line
			(start -0.3048 0.9906)
			(end 0.3048 0.9906)
			(stroke
				(width 0.1)
				(type default)
			)
			(layer "F.Fab")
		)
		(pad "1" smd rect
			(at 0 0 90)
			(size 0.508 0.508)
			(layers "F.Cu" "F.Mask" "F.Paste")
			(net "VR_FET_SW_P12V_STBY_PVCCIN_CPU1")
		)
		(pad "2" smd rect
			(at 0 0.889 90)
			(size 0.508 0.508)
			(layers "F.Cu" "F.Mask" "F.Paste")
			(net "GND")
		)
		(zone
			(layer "F.Cu")
			(hatch none 0.5)
			(connect_pads
				(clearance 0)
			)
			(min_thickness 0.25)
			(keepout
				(tracks allowed)
				(vias not_allowed)
				(pads allowed)
				(copperpour not_allowed)
				(footprints allowed)
			)
			(placement
				(enabled no)
				(sheetname "")
			)
			(fill
				(thermal_gap 0.5)
				(thermal_bridge_width 0.5)
				(island_removal_mode 0)
			)
			(polygon
				(pts
					(xy 32.921194 -102.539292) (xy 32.921194 -102.031292) (xy 33.302194 -102.031292) (xy 33.302194 -102.539292)
				)
			)
		)
		(zone
			(layer "F.Cu")
			(hatch none 0.5)
			(connect_pads
				(clearance 0)
			)
			(min_thickness 0.25)
			(keepout
				(tracks not_allowed)
				(vias allowed)
				(pads allowed)
				(copperpour not_allowed)
				(footprints allowed)
			)
			(placement
				(enabled no)
				(sheetname "")
			)
			(fill
				(thermal_gap 0.5)
				(thermal_bridge_width 0.5)
				(island_removal_mode 0)
			)
			(polygon
				(pts
					(xy 32.921194 -102.539292) (xy 32.921194 -102.031292) (xy 33.302194 -102.031292) (xy 33.302194 -102.539292)
				)
			)
		)
	)
	(footprint ""
		(layer "F.Cu")
		(at 336.2706 -129.0955)
		(property "Reference" "R7B11"
			(at 0 0 0)
			(layer "F.SilkS")
			(hide yes)
			(effects
				(font
					(size 1.27 1.27)
				)
			)
		)
		(property "Value" ""
			(at 0 0 0)
			(layer "F.Fab")
			(effects
				(font
					(size 1.27 1.27)
				)
			)
		)
		(duplicate_pad_numbers_are_jumpers no)
		(fp_poly
			(pts
				(xy -0.2794 -0.1016) (xy 0.2794 -0.1016) (xy 0.2794 0.9906) (xy -0.2794 0.9906)
			)
			(stroke
				(width 0)
				(type default)
			)
			(fill no)
			(layer "F.CrtYd")
		)
		(fp_line
			(start -0.2794 -0.1016)
			(end -0.2794 0.9906)
			(stroke
				(width 0.1)
				(type default)
			)
			(layer "F.Fab")
		)
		(fp_line
			(start -0.2794 0.9906)
			(end 0.2794 0.9906)
			(stroke
				(width 0.1)
				(type default)
			)
			(layer "F.Fab")
		)
		(fp_line
			(start 0.2794 -0.1016)
			(end -0.2794 -0.1016)
			(stroke
				(width 0.1)
				(type default)
			)
			(layer "F.Fab")
		)
		(fp_line
			(start 0.2794 0.9906)
			(end 0.2794 -0.1016)
			(stroke
				(width 0.1)
				(type default)
			)
			(layer "F.Fab")
		)
		(pad "1" smd rect
			(at 0 0)
			(size 0.508 0.508)
			(layers "F.Cu" "F.Mask" "F.Paste")
			(net "PVPP_DEF")
		)
		(pad "2" smd rect
			(at 0 0.889)
			(size 0.508 0.508)
			(layers "F.Cu" "F.Mask" "F.Paste")
			(net "VSENSE_PVPP_DEF")
		)
		(zone
			(layer "F.Cu")
			(hatch none 0.5)
			(connect_pads
				(clearance 0)
			)
			(min_thickness 0.25)
			(keepout
				(tracks allowed)
				(vias not_allowed)
				(pads allowed)
				(copperpour not_allowed)
				(footprints allowed)
			)
			(placement
				(enabled no)
				(sheetname "")
			)
			(fill
				(thermal_gap 0.5)
				(thermal_bridge_width 0.5)
				(island_removal_mode 0)
			)
			(polygon
				(pts
					(xy 336.0166 -128.8415) (xy 336.5246 -128.8415) (xy 336.5246 -128.4605) (xy 336.0166 -128.4605)
				)
			)
		)
		(zone
			(layer "F.Cu")
			(hatch none 0.5)
			(connect_pads
				(clearance 0)
			)
			(min_thickness 0.25)
			(keepout
				(tracks not_allowed)
				(vias allowed)
				(pads allowed)
				(copperpour not_allowed)
				(footprints allowed)
			)
			(placement
				(enabled no)
				(sheetname "")
			)
			(fill
				(thermal_gap 0.5)
				(thermal_bridge_width 0.5)
				(island_removal_mode 0)
			)
			(polygon
				(pts
					(xy 336.0166 -128.4605) (xy 336.5246 -128.4605) (xy 336.5246 -128.8415) (xy 336.0166 -128.8415)
				)
			)
		)
	)
)
